# T6G (Grand Teton) — schematic netlist excerpt (pin names and nets, part order shuffled) for the footprints in the layout excerpt that follows; sources: Cadence DE-HDL packaged netlist, KiCad conversion of 04192023_DAF0TMB3IC0_F0TG_MB_C_brd_V02_OCP.brd

U39  TCA9548APWR  IC  pkg TSSOP24XA  page 252
  A0  = PCA9548_PCIE0_ADDR0
  A1  = PCA9548_PCIE0_ADDR1
  \reset#\  = PU_RST_SMB_PCIE2_N
  SD0  = SMB_VR_3V3AUX_SDA_R6
  SC0  = SMB_VR_3V3AUX_SCL_R6
  SD1  = SMB_LM75_0_3V3AUX_SDA_R
  SC1  = SMB_LM75_0_3V3AUX_SCL_R
  SD2  = SMB_LM75_1_3V3AUX_SDA_R
  SC2  = SMB_LM75_1_3V3AUX_SCL_R
  SD3  = SMB_LM75_2_3V3AUX_SDA_R
  SC3  = SMB_LM75_2_3V3AUX_SCL_R
  GND  = GND
  SD4  = SMB_LM75_3_3V3AUX_SDA_R
  SC4  = SMB_LM75_3_3V3AUX_SCL_R
  SD5  = SMB_P12V_HSC_SDA_R
  SC5  = SMB_P12V_HSC_SCL_R
  SD6  = SMB_ADC_SDA
  SC6  = SMB_ADC_SCL
  SD7  = NC
  SC7  = NC
  A2  = PCA9548_PCIE0_ADDR2
  SCL  = SMB_VR_SENSOR_3V3AUX_SCL_R
  SDA  = SMB_VR_SENSOR_3V3AUX_SDA_R
  VCC  = P3V3_AUX

(kicad_pcb
	(version 20260206)
	(generator "pcbnew")
	(generator_version "10.0")
	(general
		(thickness 1.6)
		(legacy_teardrops no)
	)
	(paper "A4")
	(title_block
		(title "04192023_DAF0TMB3IC0_F0TG_MB_C_brd_V02_OCP.brd")
		(comment 1 "Grand Teton / footprints 1097-1097 of 8354")
	)
	(layers
		(0 "F.Cu" signal "TOP")
		(4 "In1.Cu" signal "GND")
		(6 "In2.Cu" signal "IN1")
		(8 "In3.Cu" signal "GND1")
		(10 "In4.Cu" signal "IN2")
		(12 "In5.Cu" signal "GND2")
		(14 "In6.Cu" signal "IN3")
		(16 "In7.Cu" signal "GND3")
		(18 "In8.Cu" signal "VCC")
		(20 "In9.Cu" signal "VCC1")
		(22 "In10.Cu" signal "GND4")
		(24 "In11.Cu" signal "IN4")
		(26 "In12.Cu" signal "GND5")
		(28 "In13.Cu" signal "IN5")
		(30 "In14.Cu" signal "GND6")
		(32 "In15.Cu" signal "IN6")
		(34 "In16.Cu" signal "GND7")
		(2 "B.Cu" signal "BOTTOM")
		(9 "F.Adhes" user "F.Adhesive")
		(11 "B.Adhes" user "B.Adhesive")
		(13 "F.Paste" user "Package Geometry/Pastemask Top")
		(15 "B.Paste" user "Package Geometry/Pastemask Bottom")
		(5 "F.SilkS" user "Ref Des/Silkscreen Top")
		(7 "B.SilkS" user "Ref Des/Silkscreen Bottom")
		(1 "F.Mask" user "Board Geometry/Soldermask Top")
		(3 "B.Mask" user "Board Geometry/Soldermask Bottom")
		(17 "Dwgs.User" user "User.Drawings")
		(19 "Cmts.User" user "User.Comments")
		(21 "Eco1.User" user "User.Eco1")
		(23 "Eco2.User" user "User.Eco2")
		(25 "Edge.Cuts" user "Board Geometry/Outline")
		(27 "Margin" user)
		(31 "F.CrtYd" user "Package Geometry/Place Bound Top")
		(29 "B.CrtYd" user "Package Geometry/Place Bound Bottom")
		(35 "F.Fab" user "Ref Des/Assembly Top")
		(33 "B.Fab" user "Ref Des/Assembly Bottom")
	)
	(footprint ""
		(layer "F.Cu")
		(at 264.174986 -119.207026)
		(property "Reference" "U39"
			(at -2.482342 -5.187696 0)
			(unlocked yes)
			(layer "F.SilkS")
			(effects
				(font
					(size 0.7874 0.5842)
					(thickness 0.1524)
				)
				(justify left)
			)
		)
		(property "Value" ""
			(at 0 0 0)
			(layer "F.Fab")
			(effects
				(font
					(size 1.27 1.27)
				)
			)
		)
		(duplicate_pad_numbers_are_jumpers no)
		(fp_line
			(start -1.8542 -3.949954)
			(end -1.8542 3.949954)
			(stroke
				(width 0.1524)
				(type default)
			)
			(layer "F.SilkS")
		)
		(fp_line
			(start -1.8542 3.949954)
			(end 1.8542 3.949954)
			(stroke
				(width 0.1524)
				(type default)
			)
			(layer "F.SilkS")
		)
		(fp_line
			(start -1.282954 -3.949954)
			(end -1.8542 -3.949954)
			(stroke
				(width 0.1524)
				(type default)
			)
			(layer "F.SilkS")
		)
		(fp_line
			(start 0 -2.667)
			(end -1.282954 -3.949954)
			(stroke
				(width 0.1524)
				(type default)
			)
			(layer "F.SilkS")
		)
		(fp_line
			(start 1.282954 -3.949954)
			(end 0 -2.667)
			(stroke
				(width 0.1524)
				(type default)
			)
			(layer "F.SilkS")
		)
		(fp_line
			(start 1.8542 -3.949954)
			(end 1.282954 -3.949954)
			(stroke
				(width 0.1524)
				(type default)
			)
			(layer "F.SilkS")
		)
		(fp_line
			(start 1.8542 3.949954)
			(end 1.8542 -3.949954)
			(stroke
				(width 0.1524)
				(type default)
			)
			(layer "F.SilkS")
		)
		(fp_poly
			(pts
				(xy -3.7846 -3.57505) (xy -4.8006 -3.06705) (xy -4.8006 -4.08305)
			)
			(stroke
				(width 0)
				(type default)
			)
			(fill yes)
			(layer "F.SilkS")
		)
		(fp_line
			(start -2.249932 -3.949954)
			(end -2.249932 3.949954)
			(stroke
				(width 0.1)
				(type default)
			)
			(layer "F.Fab")
		)
		(fp_line
			(start -2.249932 3.949954)
			(end 2.249932 3.949954)
			(stroke
				(width 0.1)
				(type default)
			)
			(layer "F.Fab")
		)
		(fp_line
			(start 2.249932 -3.949954)
			(end -2.249932 -3.949954)
			(stroke
				(width 0.1)
				(type default)
			)
			(layer "F.Fab")
		)
		(fp_line
			(start 2.249932 3.949954)
			(end 2.249932 -3.949954)
			(stroke
				(width 0.1)
				(type default)
			)
			(layer "F.Fab")
		)
		(fp_poly
			(pts
				(xy -4.8006 -4.08305) (xy -4.8006 -3.06705) (xy -3.7846 -3.57505)
			)
			(stroke
				(width 0)
				(type default)
			)
			(fill yes)
			(layer "F.Fab")
		)
		(pad "1" smd rect
			(at -2.800096 -3.57505 270)
			(size 0.3048 1.6002)
			(layers "F.Cu" "F.Mask" "F.Paste")
			(net "PCA9548_PCIE0_ADDR0")
		)
		(pad "2" smd rect
			(at -2.800096 -2.925064 270)
			(size 0.3048 1.6002)
			(layers "F.Cu" "F.Mask" "F.Paste")
			(net "PCA9548_PCIE0_ADDR1")
		)
		(pad "3" smd rect
			(at -2.800096 -2.275078 270)
			(size 0.3048 1.6002)
			(layers "F.Cu" "F.Mask" "F.Paste")
			(net "PU_RST_SMB_PCIE2_N")
		)
		(pad "4" smd rect
			(at -2.800096 -1.625092 270)
			(size 0.3048 1.6002)
			(layers "F.Cu" "F.Mask" "F.Paste")
			(net "SMB_VR_3V3AUX_SDA_R6")
		)
		(pad "5" smd rect
			(at -2.800096 -0.975106 270)
			(size 0.3048 1.6002)
			(layers "F.Cu" "F.Mask" "F.Paste")
			(net "SMB_VR_3V3AUX_SCL_R6")
		)
		(pad "6" smd rect
			(at -2.800096 -0.32512 270)
			(size 0.3048 1.6002)
			(layers "F.Cu" "F.Mask" "F.Paste")
			(net "SMB_LM75_0_3V3AUX_SDA_R")
		)
		(pad "7" smd rect
			(at -2.800096 0.32512 270)
			(size 0.3048 1.6002)
			(layers "F.Cu" "F.Mask" "F.Paste")
			(net "SMB_LM75_0_3V3AUX_SCL_R")
		)
		(pad "8" smd rect
			(at -2.800096 0.975106 270)
			(size 0.3048 1.6002)
			(layers "F.Cu" "F.Mask" "F.Paste")
			(net "SMB_LM75_1_3V3AUX_SDA_R")
		)
		(pad "9" smd rect
			(at -2.800096 1.625092 270)
			(size 0.3048 1.6002)
			(layers "F.Cu" "F.Mask" "F.Paste")
			(net "SMB_LM75_1_3V3AUX_SCL_R")
		)
		(pad "10" smd rect
			(at -2.800096 2.275078 270)
			(size 0.3048 1.6002)
			(layers "F.Cu" "F.Mask" "F.Paste")
			(net "SMB_LM75_2_3V3AUX_SDA_R")
		)
		(pad "11" smd rect
			(at -2.800096 2.925064 270)
			(size 0.3048 1.6002)
			(layers "F.Cu" "F.Mask" "F.Paste")
			(net "SMB_LM75_2_3V3AUX_SCL_R")
		)
		(pad "12" smd rect
			(at -2.800096 3.57505 270)
			(size 0.3048 1.6002)
			(layers "F.Cu" "F.Mask" "F.Paste")
			(net "GND")
		)
		(pad "13" smd rect
			(at 2.800096 3.57505 270)
			(size 0.3048 1.6002)
			(layers "F.Cu" "F.Mask" "F.Paste")
			(net "SMB_LM75_3_3V3AUX_SDA_R")
		)
		(pad "14" smd rect
			(at 2.800096 2.925064 270)
			(size 0.3048 1.6002)
			(layers "F.Cu" "F.Mask" "F.Paste")
			(net "SMB_LM75_3_3V3AUX_SCL_R")
		)
		(pad "15" smd rect
			(at 2.800096 2.275078 270)
			(size 0.3048 1.6002)
			(layers "F.Cu" "F.Mask" "F.Paste")
			(net "SMB_P12V_HSC_SDA_R")
		)
		(pad "16" smd rect
			(at 2.800096 1.625092 270)
			(size 0.3048 1.6002)
			(layers "F.Cu" "F.Mask" "F.Paste")
			(net "SMB_P12V_HSC_SCL_R")
		)
		(pad "17" smd rect
			(at 2.800096 0.975106 270)
			(size 0.3048 1.6002)
			(layers "F.Cu" "F.Mask" "F.Paste")
			(net "SMB_ADC_SDA")
		)
		(pad "18" smd rect
			(at 2.800096 0.32512 270)
			(size 0.3048 1.6002)
			(layers "F.Cu" "F.Mask" "F.Paste")
			(net "SMB_ADC_SCL")
		)
		(pad "19" smd rect
			(at 2.800096 -0.32512 270)
			(size 0.3048 1.6002)
			(layers "F.Cu" "F.Mask" "F.Paste")
			(net "Net_10755")
		)
		(pad "20" smd rect
			(at 2.800096 -0.975106 270)
			(size 0.3048 1.6002)
			(layers "F.Cu" "F.Mask" "F.Paste")
			(net "Net_10756")
		)
		(pad "21" smd rect
			(at 2.800096 -1.625092 270)
			(size 0.3048 1.6002)
			(layers "F.Cu" "F.Mask" "F.Paste")
			(net "PCA9548_PCIE0_ADDR2")
		)
		(pad "22" smd rect
			(at 2.800096 -2.275078 270)
			(size 0.3048 1.6002)
			(layers "F.Cu" "F.Mask" "F.Paste")
			(net "SMB_VR_SENSOR_3V3AUX_SCL_R")
		)
		(pad "23" smd rect
			(at 2.800096 -2.925064 270)
			(size 0.3048 1.6002)
			(layers "F.Cu" "F.Mask" "F.Paste")
			(net "SMB_VR_SENSOR_3V3AUX_SDA_R")
		)
		(pad "24" smd rect
			(at 2.800096 -3.57505 270)
			(size 0.3048 1.6002)
			(layers "F.Cu" "F.Mask" "F.Paste")
			(net "P3V3_AUX")
		)
	)
)
